(kicad_pcb
	(version 20260206)
	(generator "pcbnew")
	(generator_version "10.0")
	(general
		(thickness 1.6)
		(legacy_teardrops no)
	)
	(paper "A4")
	(title_block
		(title "baseboard — 13948-1b.1110WZS1818.brd")
		(comment 1 "Honey Badger (Wiwynn) / footprints 1749-1756 of 2523")
	)
	(layers
		(0 "F.Cu" signal "TOP")
		(4 "In1.Cu" signal "L2GND")
		(6 "In2.Cu" signal "L3")
		(8 "In3.Cu" signal "L4VCC")
		(10 "In4.Cu" signal "L5VCC")
		(12 "In5.Cu" signal "L6")
		(14 "In6.Cu" signal "L7GND")
		(2 "B.Cu" signal "BOTTOM")
		(9 "F.Adhes" user "F.Adhesive")
		(11 "B.Adhes" user "B.Adhesive")
		(13 "F.Paste" user "Package Geometry/Pastemask Top")
		(15 "B.Paste" user "Package Geometry/Pastemask Bottom")
		(5 "F.SilkS" user "Ref Des/Silkscreen Top")
		(7 "B.SilkS" user "Ref Des/Silkscreen Bottom")
		(1 "F.Mask" user "Board Geometry/Soldermask Top")
		(3 "B.Mask" user "Board Geometry/Soldermask Bottom")
		(17 "Dwgs.User" user "User.Drawings")
		(19 "Cmts.User" user "User.Comments")
		(21 "Eco1.User" user "User.Eco1")
		(23 "Eco2.User" user "User.Eco2")
		(25 "Edge.Cuts" user "Board Geometry/Outline")
		(27 "Margin" user)
		(31 "F.CrtYd" user "Package Geometry/Place Bound Top")
		(29 "B.CrtYd" user "Package Geometry/Place Bound Bottom")
		(35 "F.Fab" user "Ref Des/Assembly Top")
		(33 "B.Fab" user "Ref Des/Assembly Bottom")
	)
	(footprint ""
		(layer "F.Cu")
		(at 311.531 -112.268)
		(property "Reference" "PR24"
			(at 0 0 0)
			(layer "F.SilkS")
			(hide yes)
			(effects
				(font
					(size 1.27 1.27)
				)
			)
		)
		(property "Value" "2K7R2J-GP"
			(at 0.064008 -3.993896 0)
			(unlocked yes)
			(layer "F.Fab")
			(hide yes)
			(effects
				(font
					(size 1.016 1.016)
					(thickness 0.1524)
				)
			)
		)
		(property "Device Type" "R402H16"
			(at 0.064008 -5.517896 0)
			(unlocked yes)
			(layer "F.Fab")
			(hide yes)
			(effects
				(font
					(size 1.016 1.016)
					(thickness 0.1524)
				)
			)
		)
		(duplicate_pad_numbers_are_jumpers no)
		(fp_line
			(start -0.508 -0.9398)
			(end -0.508 0.9398)
			(stroke
				(width 0.1524)
				(type default)
			)
			(layer "F.SilkS")
		)
		(fp_line
			(start 0.508 -0.9398)
			(end -0.508 -0.9398)
			(stroke
				(width 0.1524)
				(type default)
			)
			(layer "F.SilkS")
		)
		(fp_rect
			(start -0.508 0.9398)
			(end 0.508 -0.9398)
			(stroke
				(width 0)
				(type default)
			)
			(fill no)
			(layer "F.CrtYd")
		)
		(fp_rect
			(start -0.508 0.9398)
			(end 0.508 -0.9398)
			(stroke
				(width 0)
				(type default)
			)
			(fill no)
			(layer "F.Fab")
		)
		(pad "1" smd custom
			(at 0 -0.4445)
			(size 0.1397 0.1397)
			(layers "F.Cu" "F.Mask" "F.Paste")
			(net "P3V3_STBY_EN")
			(options
				(clearance outline)
				(anchor circle)
			)
			(primitives
				(gr_poly
					(pts
						(arc
							(start -0.1778 -0.2794)
							(mid -0.249642 -0.249642)
							(end -0.2794 -0.1778)
						)
						(arc
							(start -0.2794 0.1778)
							(mid -0.249642 0.249642)
							(end -0.1778 0.2794)
						)
						(arc
							(start 0.1778 0.2794)
							(mid 0.249642 0.249642)
							(end 0.2794 0.1778)
						)
						(arc
							(start 0.2794 -0.1778)
							(mid 0.249642 -0.249642)
							(end 0.1778 -0.2794)
						)
					)
					(width 0)
					(fill yes)
				)
			)
		)
		(pad "2" smd custom
			(at 0 0.4445)
			(size 0.1397 0.1397)
			(layers "F.Cu" "F.Mask" "F.Paste")
			(net "AGND_P3V3_STBY")
			(options
				(clearance outline)
				(anchor circle)
			)
			(primitives
				(gr_poly
					(pts
						(arc
							(start -0.1778 -0.2794)
							(mid -0.249642 -0.249642)
							(end -0.2794 -0.1778)
						)
						(arc
							(start -0.2794 0.1778)
							(mid -0.249642 0.249642)
							(end -0.1778 0.2794)
						)
						(arc
							(start 0.1778 0.2794)
							(mid 0.249642 0.249642)
							(end 0.2794 0.1778)
						)
						(arc
							(start 0.2794 -0.1778)
							(mid 0.249642 -0.249642)
							(end 0.1778 -0.2794)
						)
					)
					(width 0)
					(fill yes)
				)
			)
		)
	)
	(footprint ""
		(layer "F.Cu")
		(at 131.318 -89.789 90)
		(property "Reference" "SC1102"
			(at 0 0 90)
			(layer "F.SilkS")
			(hide yes)
			(effects
				(font
					(size 1.27 1.27)
				)
			)
		)
		(property "Value" "SCD01U10V1KX-GP"
			(at -2.8321 -1.7399 90)
			(unlocked yes)
			(layer "F.Fab")
			(hide yes)
			(effects
				(font
					(size 1.016 1.016)
					(thickness 0.1524)
				)
			)
		)
		(property "Device Type" "C0201H13"
			(at -2.8321 -3.2639 90)
			(unlocked yes)
			(layer "F.Fab")
			(hide yes)
			(effects
				(font
					(size 1.016 1.016)
					(thickness 0.1524)
				)
			)
		)
		(duplicate_pad_numbers_are_jumpers no)
		(fp_rect
			(start -0.2794 0.6477)
			(end 0.2794 -0.6477)
			(stroke
				(width 0)
				(type default)
			)
			(fill no)
			(layer "F.CrtYd")
		)
		(fp_rect
			(start -0.2794 0.6477)
			(end 0.2794 -0.6477)
			(stroke
				(width 0)
				(type default)
			)
			(fill no)
			(layer "F.Fab")
		)
		(pad "1" smd custom
			(at 0 -0.2794 90)
			(size 0.0762 0.0762)
			(layers "F.Cu" "F.Mask" "F.Paste")
			(net "3X24_SAS_TX18_P")
			(options
				(clearance outline)
				(anchor circle)
			)
			(primitives
				(gr_poly
					(pts
						(arc
							(start 0.1524 -0.127)
							(mid 0.137521 -0.162921)
							(end 0.1016 -0.1778)
						)
						(arc
							(start -0.1016 -0.1778)
							(mid -0.137521 -0.162921)
							(end -0.1524 -0.127)
						)
						(arc
							(start -0.1524 0.127)
							(mid -0.137521 0.162921)
							(end -0.1016 0.1778)
						)
						(arc
							(start 0.1016 0.1778)
							(mid 0.137521 0.162921)
							(end 0.1524 0.127)
						)
					)
					(width 0)
					(fill yes)
				)
			)
		)
		(pad "2" smd custom
			(at 0 0.2794 90)
			(size 0.0762 0.0762)
			(layers "F.Cu" "F.Mask" "F.Paste")
			(net "SAS_EXP2CONN_TX_P_22")
			(options
				(clearance outline)
				(anchor circle)
			)
			(primitives
				(gr_poly
					(pts
						(arc
							(start 0.1524 -0.127)
							(mid 0.137521 -0.162921)
							(end 0.1016 -0.1778)
						)
						(arc
							(start -0.1016 -0.1778)
							(mid -0.137521 -0.162921)
							(end -0.1524 -0.127)
						)
						(arc
							(start -0.1524 0.127)
							(mid -0.137521 0.162921)
							(end -0.1016 0.1778)
						)
						(arc
							(start 0.1016 0.1778)
							(mid 0.137521 0.162921)
							(end 0.1524 0.127)
						)
					)
					(width 0)
					(fill yes)
				)
			)
		)
	)
	(footprint ""
		(layer "F.Cu")
		(at 117.221 -71.628 -90)
		(property "Reference" "R588"
			(at 0 0 270)
			(layer "F.SilkS")
			(hide yes)
			(effects
				(font
					(size 1.27 1.27)
				)
			)
		)
		(property "Value" "0R2J-2-GP"
			(at 0.064008 -3.993896 270)
			(unlocked yes)
			(layer "F.Fab")
			(hide yes)
			(effects
				(font
					(size 1.016 1.016)
					(thickness 0.1524)
				)
			)
		)
		(property "Device Type" "R402H16"
			(at 0.064008 -5.517896 270)
			(unlocked yes)
			(layer "F.Fab")
			(hide yes)
			(effects
				(font
					(size 1.016 1.016)
					(thickness 0.1524)
				)
			)
		)
		(duplicate_pad_numbers_are_jumpers no)
		(fp_line
			(start -0.508 -0.9398)
			(end -0.508 0.9398)
			(stroke
				(width 0.1524)
				(type default)
			)
			(layer "F.SilkS")
		)
		(fp_line
			(start 0.508 -0.9398)
			(end -0.508 -0.9398)
			(stroke
				(width 0.1524)
				(type default)
			)
			(layer "F.SilkS")
		)
		(fp_rect
			(start -0.508 0.9398)
			(end 0.508 -0.9398)
			(stroke
				(width 0)
				(type default)
			)
			(fill no)
			(layer "F.CrtYd")
		)
		(fp_rect
			(start -0.508 0.9398)
			(end 0.508 -0.9398)
			(stroke
				(width 0)
				(type default)
			)
			(fill no)
			(layer "F.Fab")
		)
		(pad "1" smd custom
			(at 0 -0.4445 270)
			(size 0.1397 0.1397)
			(layers "F.Cu" "F.Mask" "F.Paste")
			(net "BMC_I2C_D_SCL")
			(options
				(clearance outline)
				(anchor circle)
			)
			(primitives
				(gr_poly
					(pts
						(arc
							(start -0.1778 -0.2794)
							(mid -0.249642 -0.249642)
							(end -0.2794 -0.1778)
						)
						(arc
							(start -0.2794 0.1778)
							(mid -0.249642 0.249642)
							(end -0.1778 0.2794)
						)
						(arc
							(start 0.1778 0.2794)
							(mid 0.249642 0.249642)
							(end 0.2794 0.1778)
						)
						(arc
							(start 0.2794 -0.1778)
							(mid 0.249642 -0.249642)
							(end 0.1778 -0.2794)
						)
					)
					(width 0)
					(fill yes)
				)
			)
		)
		(pad "2" smd custom
			(at 0 0.4445 270)
			(size 0.1397 0.1397)
			(layers "F.Cu" "F.Mask" "F.Paste")
			(net "TEMP_4_SCL")
			(options
				(clearance outline)
				(anchor circle)
			)
			(primitives
				(gr_poly
					(pts
						(arc
							(start -0.1778 -0.2794)
							(mid -0.249642 -0.249642)
							(end -0.2794 -0.1778)
						)
						(arc
							(start -0.2794 0.1778)
							(mid -0.249642 0.249642)
							(end -0.1778 0.2794)
						)
						(arc
							(start 0.1778 0.2794)
							(mid 0.249642 0.249642)
							(end 0.2794 0.1778)
						)
						(arc
							(start 0.2794 -0.1778)
							(mid 0.249642 -0.249642)
							(end 0.1778 -0.2794)
						)
					)
					(width 0)
					(fill yes)
				)
			)
		)
	)
	(footprint ""
		(layer "F.Cu")
		(at 348.390718 -154.155648 -90)
		(property "Reference" "R534"
			(at 0 0 270)
			(layer "F.SilkS")
			(hide yes)
			(effects
				(font
					(size 1.27 1.27)
				)
			)
		)
		(property "Value" "0R2J-2-GP"
			(at 0.064008 -3.993896 270)
			(unlocked yes)
			(layer "F.Fab")
			(hide yes)
			(effects
				(font
					(size 1.016 1.016)
					(thickness 0.1524)
				)
			)
		)
		(property "Device Type" "R402H16"
			(at 0.064008 -5.517896 270)
			(unlocked yes)
			(layer "F.Fab")
			(hide yes)
			(effects
				(font
					(size 1.016 1.016)
					(thickness 0.1524)
				)
			)
		)
		(duplicate_pad_numbers_are_jumpers no)
		(fp_line
			(start -0.508 -0.9398)
			(end -0.508 0.9398)
			(stroke
				(width 0.1524)
				(type default)
			)
			(layer "F.SilkS")
		)
		(fp_line
			(start 0.508 -0.9398)
			(end -0.508 -0.9398)
			(stroke
				(width 0.1524)
				(type default)
			)
			(layer "F.SilkS")
		)
		(fp_rect
			(start -0.508 0.9398)
			(end 0.508 -0.9398)
			(stroke
				(width 0)
				(type default)
			)
			(fill no)
			(layer "F.CrtYd")
		)
		(fp_rect
			(start -0.508 0.9398)
			(end 0.508 -0.9398)
			(stroke
				(width 0)
				(type default)
			)
			(fill no)
			(layer "F.Fab")
		)
		(pad "1" smd custom
			(at 0 -0.4445 270)
			(size 0.1397 0.1397)
			(layers "F.Cu" "F.Mask" "F.Paste")
			(net "BMC_USB1_HDN2")
			(options
				(clearance outline)
				(anchor circle)
			)
			(primitives
				(gr_poly
					(pts
						(arc
							(start -0.1778 -0.2794)
							(mid -0.249642 -0.249642)
							(end -0.2794 -0.1778)
						)
						(arc
							(start -0.2794 0.1778)
							(mid -0.249642 0.249642)
							(end -0.1778 0.2794)
						)
						(arc
							(start 0.1778 0.2794)
							(mid 0.249642 0.249642)
							(end 0.2794 0.1778)
						)
						(arc
							(start 0.2794 -0.1778)
							(mid 0.249642 -0.249642)
							(end 0.1778 -0.2794)
						)
					)
					(width 0)
					(fill yes)
				)
			)
		)
		(pad "2" smd custom
			(at 0 0.4445 270)
			(size 0.1397 0.1397)
			(layers "F.Cu" "F.Mask" "F.Paste")
			(net "USB_P4_DN")
			(options
				(clearance outline)
				(anchor circle)
			)
			(primitives
				(gr_poly
					(pts
						(arc
							(start -0.1778 -0.2794)
							(mid -0.249642 -0.249642)
							(end -0.2794 -0.1778)
						)
						(arc
							(start -0.2794 0.1778)
							(mid -0.249642 0.249642)
							(end -0.1778 0.2794)
						)
						(arc
							(start 0.1778 0.2794)
							(mid 0.249642 0.249642)
							(end 0.2794 0.1778)
						)
						(arc
							(start 0.2794 -0.1778)
							(mid 0.249642 -0.249642)
							(end 0.1778 -0.2794)
						)
					)
					(width 0)
					(fill yes)
				)
			)
		)
	)
	(footprint ""
		(layer "F.Cu")
		(at 86.49716 -38.608 -90)
		(property "Reference" "SC884"
			(at 0 0 270)
			(layer "F.SilkS")
			(hide yes)
			(effects
				(font
					(size 1.27 1.27)
				)
			)
		)
		(property "Value" "SCD01U10V1KX-GP"
			(at -2.8321 -1.7399 270)
			(unlocked yes)
			(layer "F.Fab")
			(hide yes)
			(effects
				(font
					(size 1.016 1.016)
					(thickness 0.1524)
				)
			)
		)
		(property "Device Type" "C0201H13"
			(at -2.8321 -3.2639 270)
			(unlocked yes)
			(layer "F.Fab")
			(hide yes)
			(effects
				(font
					(size 1.016 1.016)
					(thickness 0.1524)
				)
			)
		)
		(duplicate_pad_numbers_are_jumpers no)
		(fp_rect
			(start -0.2794 0.6477)
			(end 0.2794 -0.6477)
			(stroke
				(width 0)
				(type default)
			)
			(fill no)
			(layer "F.CrtYd")
		)
		(fp_rect
			(start -0.2794 0.6477)
			(end 0.2794 -0.6477)
			(stroke
				(width 0)
				(type default)
			)
			(fill no)
			(layer "F.Fab")
		)
		(pad "1" smd custom
			(at 0 -0.2794 270)
			(size 0.0762 0.0762)
			(layers "F.Cu" "F.Mask" "F.Paste")
			(net "SAS3008_RAID_TX_C_P3")
			(options
				(clearance outline)
				(anchor circle)
			)
			(primitives
				(gr_poly
					(pts
						(arc
							(start 0.1524 -0.127)
							(mid 0.137521 -0.162921)
							(end 0.1016 -0.1778)
						)
						(arc
							(start -0.1016 -0.1778)
							(mid -0.137521 -0.162921)
							(end -0.1524 -0.127)
						)
						(arc
							(start -0.1524 0.127)
							(mid -0.137521 0.162921)
							(end -0.1016 0.1778)
						)
						(arc
							(start 0.1016 0.1778)
							(mid 0.137521 0.162921)
							(end 0.1524 0.127)
						)
					)
					(width 0)
					(fill yes)
				)
			)
		)
		(pad "2" smd custom
			(at 0 0.2794 270)
			(size 0.0762 0.0762)
			(layers "F.Cu" "F.Mask" "F.Paste")
			(net "SAS3008_RAID_TX_P3")
			(options
				(clearance outline)
				(anchor circle)
			)
			(primitives
				(gr_poly
					(pts
						(arc
							(start 0.1524 -0.127)
							(mid 0.137521 -0.162921)
							(end 0.1016 -0.1778)
						)
						(arc
							(start -0.1016 -0.1778)
							(mid -0.137521 -0.162921)
							(end -0.1524 -0.127)
						)
						(arc
							(start -0.1524 0.127)
							(mid -0.137521 0.162921)
							(end -0.1016 0.1778)
						)
						(arc
							(start 0.1016 0.1778)
							(mid 0.137521 0.162921)
							(end 0.1524 0.127)
						)
					)
					(width 0)
					(fill yes)
				)
			)
		)
	)
	(footprint ""
		(layer "F.Cu")
		(at 318.389 -48.006 90)
		(property "Reference" "TC13"
			(at 0 0 90)
			(layer "F.SilkS")
			(hide yes)
			(effects
				(font
					(size 1.27 1.27)
				)
			)
		)
		(property "Value" "SC47U16V0MX-GP"
			(at -0.00254 -4.78536 90)
			(unlocked yes)
			(layer "F.Fab")
			(hide yes)
			(effects
				(font
					(size 1.016 1.016)
					(thickness 0.1524)
				)
			)
		)
		(property "Device Type" "C1210H107"
			(at -0.00254 -6.38048 90)
			(unlocked yes)
			(layer "F.Fab")
			(hide yes)
			(effects
				(font
					(size 1.016 1.016)
					(thickness 0.1524)
				)
			)
		)
		(duplicate_pad_numbers_are_jumpers no)
		(fp_line
			(start 1.5748 -2.3368)
			(end -1.5748 -2.3368)
			(stroke
				(width 0.1524)
				(type default)
			)
			(layer "F.SilkS")
		)
		(fp_line
			(start -1.5748 -2.3368)
			(end -1.5748 -0.762)
			(stroke
				(width 0.1524)
				(type default)
			)
			(layer "F.SilkS")
		)
		(fp_line
			(start 1.5748 -0.762)
			(end 1.5748 -2.3368)
			(stroke
				(width 0.1524)
				(type default)
			)
			(layer "F.SilkS")
		)
		(fp_line
			(start -1.5748 0.762)
			(end -1.5748 2.3368)
			(stroke
				(width 0.1524)
				(type default)
			)
			(layer "F.SilkS")
		)
		(fp_line
			(start 1.5748 2.3368)
			(end 1.5748 0.762)
			(stroke
				(width 0.1524)
				(type default)
			)
			(layer "F.SilkS")
		)
		(fp_line
			(start -1.5748 2.3368)
			(end 1.5748 2.3368)
			(stroke
				(width 0.1524)
				(type default)
			)
			(layer "F.SilkS")
		)
		(fp_rect
			(start -1.651 2.413)
			(end 1.651 -2.413)
			(stroke
				(width 0)
				(type default)
			)
			(fill no)
			(layer "F.CrtYd")
		)
		(fp_poly
			(pts
				(xy 1.651 2.413) (xy 1.651 -2.413) (xy -1.651 -2.413) (xy -1.651 2.413)
			)
			(stroke
				(width 0)
				(type default)
			)
			(fill no)
			(layer "F.Fab")
		)
		(pad "1" smd rect
			(at 0 -1.4732 90)
			(size 2.794 1.397)
			(layers "F.Cu" "F.Mask" "F.Paste")
			(net "P5V_STBY")
		)
		(pad "2" smd rect
			(at 0 1.4732 90)
			(size 2.794 1.397)
			(layers "F.Cu" "F.Mask" "F.Paste")
			(net "GND")
		)
	)
	(footprint ""
		(layer "F.Cu")
		(at 115.96497 -114.3 180)
		(property "Reference" "SC1074"
			(at 0 0 180)
			(layer "F.SilkS")
			(hide yes)
			(effects
				(font
					(size 1.27 1.27)
				)
			)
		)
		(property "Value" "SCD01U10V1KX-GP"
			(at -2.8321 -1.7399 180)
			(unlocked yes)
			(layer "F.Fab")
			(hide yes)
			(effects
				(font
					(size 1.016 1.016)
					(thickness 0.1524)
				)
			)
		)
		(property "Device Type" "C0201H13"
			(at -2.8321 -3.2639 180)
			(unlocked yes)
			(layer "F.Fab")
			(hide yes)
			(effects
				(font
					(size 1.016 1.016)
					(thickness 0.1524)
				)
			)
		)
		(duplicate_pad_numbers_are_jumpers no)
		(fp_rect
			(start -0.2794 0.6477)
			(end 0.2794 -0.6477)
			(stroke
				(width 0)
				(type default)
			)
			(fill no)
			(layer "F.CrtYd")
		)
		(fp_rect
			(start -0.2794 0.6477)
			(end 0.2794 -0.6477)
			(stroke
				(width 0)
				(type default)
			)
			(fill no)
			(layer "F.Fab")
		)
		(pad "1" smd custom
			(at 0 -0.2794 180)
			(size 0.0762 0.0762)
			(layers "F.Cu" "F.Mask" "F.Paste")
			(net "SAS_HDD_TX3_N")
			(options
				(clearance outline)
				(anchor circle)
			)
			(primitives
				(gr_poly
					(pts
						(arc
							(start 0.1524 -0.127)
							(mid 0.137521 -0.162921)
							(end 0.1016 -0.1778)
						)
						(arc
							(start -0.1016 -0.1778)
							(mid -0.137521 -0.162921)
							(end -0.1524 -0.127)
						)
						(arc
							(start -0.1524 0.127)
							(mid -0.137521 0.162921)
							(end -0.1016 0.1778)
						)
						(arc
							(start 0.1016 0.1778)
							(mid 0.137521 0.162921)
							(end 0.1524 0.127)
						)
					)
					(width 0)
					(fill yes)
				)
			)
		)
		(pad "2" smd custom
			(at 0 0.2794 180)
			(size 0.0762 0.0762)
			(layers "F.Cu" "F.Mask" "F.Paste")
			(net "SAS_HDD_REDV_TX7_N")
			(options
				(clearance outline)
				(anchor circle)
			)
			(primitives
				(gr_poly
					(pts
						(arc
							(start 0.1524 -0.127)
							(mid 0.137521 -0.162921)
							(end 0.1016 -0.1778)
						)
						(arc
							(start -0.1016 -0.1778)
							(mid -0.137521 -0.162921)
							(end -0.1524 -0.127)
						)
						(arc
							(start -0.1524 0.127)
							(mid -0.137521 0.162921)
							(end -0.1016 0.1778)
						)
						(arc
							(start 0.1016 0.1778)
							(mid 0.137521 0.162921)
							(end 0.1524 0.127)
						)
					)
					(width 0)
					(fill yes)
				)
			)
		)
	)
	(footprint ""
		(layer "F.Cu")
		(at 86.49716 -39.624 -90)
		(property "Reference" "SC893"
			(at 0 0 270)
			(layer "F.SilkS")
			(hide yes)
			(effects
				(font
					(size 1.27 1.27)
				)
			)
		)
		(property "Value" "SCD01U10V1KX-GP"
			(at -2.8321 -1.7399 270)
			(unlocked yes)
			(layer "F.Fab")
			(hide yes)
			(effects
				(font
					(size 1.016 1.016)
					(thickness 0.1524)
				)
			)
		)
		(property "Device Type" "C0201H13"
			(at -2.8321 -3.2639 270)
			(unlocked yes)
			(layer "F.Fab")
			(hide yes)
			(effects
				(font
					(size 1.016 1.016)
					(thickness 0.1524)
				)
			)
		)
		(duplicate_pad_numbers_are_jumpers no)
		(fp_rect
			(start -0.2794 0.6477)
			(end 0.2794 -0.6477)
			(stroke
				(width 0)
				(type default)
			)
			(fill no)
			(layer "F.CrtYd")
		)
		(fp_rect
			(start -0.2794 0.6477)
			(end 0.2794 -0.6477)
			(stroke
				(width 0)
				(type default)
			)
			(fill no)
			(layer "F.Fab")
		)
		(pad "1" smd custom
			(at 0 -0.2794 270)
			(size 0.0762 0.0762)
			(layers "F.Cu" "F.Mask" "F.Paste")
			(net "SAS3008_RAID_TX_C_N7")
			(options
				(clearance outline)
				(anchor circle)
			)
			(primitives
				(gr_poly
					(pts
						(arc
							(start 0.1524 -0.127)
							(mid 0.137521 -0.162921)
							(end 0.1016 -0.1778)
						)
						(arc
							(start -0.1016 -0.1778)
							(mid -0.137521 -0.162921)
							(end -0.1524 -0.127)
						)
						(arc
							(start -0.1524 0.127)
							(mid -0.137521 0.162921)
							(end -0.1016 0.1778)
						)
						(arc
							(start 0.1016 0.1778)
							(mid 0.137521 0.162921)
							(end 0.1524 0.127)
						)
					)
					(width 0)
					(fill yes)
				)
			)
		)
		(pad "2" smd custom
			(at 0 0.2794 270)
			(size 0.0762 0.0762)
			(layers "F.Cu" "F.Mask" "F.Paste")
			(net "IOC_RAID_TX_N7")
			(options
				(clearance outline)
				(anchor circle)
			)
			(primitives
				(gr_poly
					(pts
						(arc
							(start 0.1524 -0.127)
							(mid 0.137521 -0.162921)
							(end 0.1016 -0.1778)
						)
						(arc
							(start -0.1016 -0.1778)
							(mid -0.137521 -0.162921)
							(end -0.1524 -0.127)
						)
						(arc
							(start -0.1524 0.127)
							(mid -0.137521 0.162921)
							(end -0.1016 0.1778)
						)
						(arc
							(start 0.1016 0.1778)
							(mid 0.137521 0.162921)
							(end 0.1524 0.127)
						)
					)
					(width 0)
					(fill yes)
				)
			)
		)
	)
)
